FILE_TYPE = CONNECTIVITY;
{Allegro Design Entry HDL 17.4-2019 S026 (4007227) 1/17/2022}
"PAGE_NUMBER" = 458;
0"NC";
1"P5E_CPU1_P3_TX_C_DP<15:8>";
2"P5E_CPU1_P3_TX_C_DP<7:0>";
3"P5E_CPU1_P3_TX_C_DN<7:0>";
4"P5E_CPU1_P3_TX_C_DN<15:8>";
5"P5E_CPU1_P3_TX_C_DN<7>";
6"P5E_CPU1_P3_TX_C_DP<7>";
7"P5E_CPU1_P3_TX_C_DP<1>";
8"P5E_CPU1_P3_TX_C_DP<2>";
9"P5E_CPU1_P3_TX_C_DP<14>";
10"P5E_CPU1_P3_TX_C_DN<14>";
11"P5E_CPU1_P3_TX_C_DN<13>";
12"P5E_CPU1_P3_TX_C_DN<1>";
13"P5E_CPU1_P3_TX_C_DP<3>";
14"P5E_CPU1_P3_TX_C_DN<15>";
15"P5E_CPU1_P3_TX_C_DN<12>";
16"P5E_CPU1_P3_TX_C_DP<8>";
17"P5E_CPU1_P3_TX_C_DP<13>";
18"P5E_CPU1_P3_TX_C_DN<3>";
19"P5E_CPU1_P3_TX_C_DN<6>";
20"P5E_CPU1_P3_TX_C_DN<5>";
21"P5E_CPU1_P3_TX_C_DP<5>";
22"P5E_CPU1_P3_TX_C_DN<2>";
23"P5E_CPU1_P3_TX_C_DP<0>";
24"P5E_CPU1_P3_TX_C_DN<4>";
25"P5E_CPU1_P3_TX_C_DN<8>";
26"P5E_CPU1_P3_TX_C_DP<9>";
27"P5E_CPU1_P3_TX_C_DN<9>";
28"P5E_CPU1_P3_TX_C_DP<10>";
29"P5E_CPU1_P3_TX_C_DN<10>";
30"P5E_CPU1_P3_TX_C_DP<11>";
31"P5E_CPU1_P3_TX_C_DN<11>";
32"P5E_CPU1_P3_TX_C_DP<12>";
33"P5E_CPU1_P3_TX_C_DN<0>";
34"P5E_CPU1_P3_TX_C_DP<4>";
35"P5E_CPU1_P3_TX_C_DP<6>";
36"P5E_CPU1_P3_TX_C_DP<15>";
%"PT5161LRS"
"8","(-7825,3925)","0","pure_quanta","I1";
;
LOCATION"U6017"
$SEC"8"
CDS_SEC"8"
MATERIAL"IC"
VALUE"PT5161LRS"
PART_TYPE"SMLF"
NEEDS_NO_SIZE"TRUE"
CDS_LMAN_SYM_OUTLINE"-350,1450,300,-1400"
CDS_LIB"pure_quanta"
PART_NUMBER"AJ051610U03";
"B_PERN7"
$PN"CD35"16;
"B_PERP7"
$PN"CB34"25;
"B_PERN6"
$PN"BU35"26;
"B_PERP6"
$PN"BR34"27;
"B_PERN5"
$PN"BK35"28;
"B_PERP5"
$PN"BH34"29;
"B_PERN4"
$PN"BC35"30;
"B_PERP4"
$PN"BA34"31;
"B_PERN3"
$PN"AT35"32;
"B_PERP3"
$PN"AP34"15;
"B_PERN2"
$PN"AJ35"17;
"B_PERP2"
$PN"AG34"11;
"B_PERN1"
$PN"AB35"10;
"B_PERP1"
$PN"Y34"9;
"B_PERN0"
$PN"R35"36;
"B_PERP0"
$PN"N34"14;
%"TAP"
"1","(-6800,4125)","0","standard","I10";
;
CDS_LIB"standard"
BODY_TYPE"PLUMBING"
HDL_TAP"TRUE";
"B \NAC \NWC"4;
"S \NAC"
BN"12"15;
%"TAP"
"1","(-6600,4025)","0","standard","I11";
;
CDS_LIB"standard"
BODY_TYPE"PLUMBING"
HDL_TAP"TRUE";
"B \NAC \NWC"1;
"S \NAC"
BN"12"32;
%"TAP"
"1","(-6800,4475)","0","standard","I12";
;
CDS_LIB"standard"
BODY_TYPE"PLUMBING"
HDL_TAP"TRUE";
"B \NAC \NWC"4;
"S \NAC"
BN"13"11;
%"TAP"
"1","(-6600,4375)","0","standard","I13";
;
CDS_LIB"standard"
BODY_TYPE"PLUMBING"
HDL_TAP"TRUE";
"B \NAC \NWC"1;
"S \NAC"
BN"13"17;
%"TAP"
"1","(-6600,4825)","0","standard","I14";
;
CDS_LIB"standard"
BODY_TYPE"PLUMBING"
HDL_TAP"TRUE";
"B \NAC \NWC"1;
"S \NAC"
BN"14"9;
%"TAP"
"1","(-6800,4725)","0","standard","I15";
;
CDS_LIB"standard"
BODY_TYPE"PLUMBING"
HDL_TAP"TRUE";
"B \NAC \NWC"4;
"S \NAC"
BN"14"10;
%"TAP"
"1","(-6800,5175)","0","standard","I16";
;
CDS_LIB"standard"
BODY_TYPE"PLUMBING"
HDL_TAP"TRUE";
"B \NAC \NWC"4;
"S \NAC"
BN"15"14;
%"TAP"
"1","(-6600,5075)","0","standard","I17";
;
CDS_LIB"standard"
BODY_TYPE"PLUMBING"
HDL_TAP"TRUE";
"B \NAC \NWC"1;
"S \NAC"
BN"15"36;
%"TAP"
"1","(-6600,2625)","0","standard","I2";
;
CDS_LIB"standard"
BODY_TYPE"PLUMBING"
HDL_TAP"TRUE";
"B \NAC \NWC"1;
"S \NAC"
BN"8"16;
%"TAP"
"1","(-2175,2675)","0","standard","I20";
;
CDS_LIB"standard"
BODY_TYPE"PLUMBING"
HDL_TAP"TRUE";
"B \NAC \NWC"3;
"S \NAC"
BN"0"33;
%"TAP"
"1","(-1975,2575)","0","standard","I21";
;
CDS_LIB"standard"
BODY_TYPE"PLUMBING"
HDL_TAP"TRUE";
"B \NAC \NWC"2;
"S \NAC"
BN"0"23;
%"TAP"
"1","(-2175,2925)","0","standard","I22";
;
CDS_LIB"standard"
BODY_TYPE"PLUMBING"
HDL_TAP"TRUE";
"B \NAC \NWC"3;
"S \NAC"
BN"1"12;
%"TAP"
"1","(-1975,3025)","0","standard","I23";
;
CDS_LIB"standard"
BODY_TYPE"PLUMBING"
HDL_TAP"TRUE";
"B \NAC \NWC"2;
"S \NAC"
BN"1"7;
%"TAP"
"1","(-2175,3375)","0","standard","I24";
;
CDS_LIB"standard"
BODY_TYPE"PLUMBING"
HDL_TAP"TRUE";
"B \NAC \NWC"3;
"S \NAC"
BN"2"22;
%"TAP"
"1","(-1975,3275)","0","standard","I25";
;
CDS_LIB"standard"
BODY_TYPE"PLUMBING"
HDL_TAP"TRUE";
"B \NAC \NWC"2;
"S \NAC"
BN"2"8;
%"TAP"
"1","(-1975,3625)","0","standard","I26";
;
CDS_LIB"standard"
BODY_TYPE"PLUMBING"
HDL_TAP"TRUE";
"B \NAC \NWC"2;
"S \NAC"
BN"3"13;
%"TAP"
"1","(-2175,3725)","0","standard","I27";
;
CDS_LIB"standard"
BODY_TYPE"PLUMBING"
HDL_TAP"TRUE";
"B \NAC \NWC"3;
"S \NAC"
BN"3"18;
%"TAP"
"1","(-2175,4075)","0","standard","I28";
;
CDS_LIB"standard"
BODY_TYPE"PLUMBING"
HDL_TAP"TRUE";
"B \NAC \NWC"3;
"S \NAC"
BN"4"24;
%"TAP"
"1","(-1975,3975)","0","standard","I29";
;
CDS_LIB"standard"
BODY_TYPE"PLUMBING"
HDL_TAP"TRUE";
"B \NAC \NWC"2;
"S \NAC"
BN"4"34;
%"TAP"
"1","(-6800,2725)","0","standard","I3";
;
CDS_LIB"standard"
BODY_TYPE"PLUMBING"
HDL_TAP"TRUE";
"B \NAC \NWC"4;
"S \NAC"
BN"8"25;
%"TAP"
"1","(-2175,4425)","0","standard","I30";
;
CDS_LIB"standard"
BODY_TYPE"PLUMBING"
HDL_TAP"TRUE";
"B \NAC \NWC"3;
"S \NAC"
BN"5"20;
%"TAP"
"1","(-1975,4325)","0","standard","I31";
;
CDS_LIB"standard"
BODY_TYPE"PLUMBING"
HDL_TAP"TRUE";
"B \NAC \NWC"2;
"S \NAC"
BN"5"21;
%"TAP"
"1","(-1975,4675)","0","standard","I32";
;
CDS_LIB"standard"
BODY_TYPE"PLUMBING"
HDL_TAP"TRUE";
"B \NAC \NWC"2;
"S \NAC"
BN"6"35;
%"TAP"
"1","(-2175,4775)","0","standard","I33";
;
CDS_LIB"standard"
BODY_TYPE"PLUMBING"
HDL_TAP"TRUE";
"B \NAC \NWC"3;
"S \NAC"
BN"6"19;
%"TAP"
"1","(-2175,5125)","0","standard","I34";
;
CDS_LIB"standard"
BODY_TYPE"PLUMBING"
HDL_TAP"TRUE";
"B \NAC \NWC"3;
"S \NAC"
BN"7"5;
%"TAP"
"1","(-1975,5025)","0","standard","I35";
;
CDS_LIB"standard"
BODY_TYPE"PLUMBING"
HDL_TAP"TRUE";
"B \NAC \NWC"2;
"S \NAC"
BN"7"6;
%"PT5161LRS"
"9","(-3200,3875)","0","pure_quanta","I38";
;
LOCATION"U6017"
$SEC"9"
CDS_SEC"9"
VALUE"PT5161LRS"
PART_TYPE"SMLF"
MATERIAL"IC"
CDS_LIB"pure_quanta"
CDS_LMAN_SYM_OUTLINE"-350,1450,300,-1400"
NEEDS_NO_SIZE"TRUE"
PART_NUMBER"AJ051610U03";
"B_PERN15"
$PN"EY35"23;
"B_PERP15"
$PN"EV34"33;
"B_PERN14"
$PN"EN35"12;
"B_PERP14"
$PN"EL34"7;
"B_PERN13"
$PN"EF35"8;
"B_PERP13"
$PN"ED34"22;
"B_PERN12"
$PN"DW35"13;
"B_PERP12"
$PN"DU34"18;
"B_PERN11"
$PN"DM35"34;
"B_PERP11"
$PN"DK34"24;
"B_PERN10"
$PN"DE35"21;
"B_PERP10"
$PN"DC34"20;
"B_PERN9"
$PN"CV35"35;
"B_PERP9"
$PN"CT34"19;
"B_PERN8"
$PN"CL35"6;
"B_PERP8"
$PN"CJ34"5;
%"TAP"
"1","(-6800,3075)","0","standard","I4";
;
CDS_LIB"standard"
BODY_TYPE"PLUMBING"
HDL_TAP"TRUE";
"B \NAC \NWC"4;
"S \NAC"
BN"9"27;
%"TAP"
"1","(-6600,2975)","0","standard","I5";
;
CDS_LIB"standard"
BODY_TYPE"PLUMBING"
HDL_TAP"TRUE";
"B \NAC \NWC"1;
"S \NAC"
BN"9"26;
%"TAP"
"1","(-6800,3425)","0","standard","I6";
;
CDS_LIB"standard"
BODY_TYPE"PLUMBING"
HDL_TAP"TRUE";
"B \NAC \NWC"4;
"S \NAC"
BN"10"29;
%"TAP"
"1","(-6600,3675)","0","standard","I7";
;
CDS_LIB"standard"
BODY_TYPE"PLUMBING"
HDL_TAP"TRUE";
"B \NAC \NWC"1;
"S \NAC"
BN"11"30;
%"TAP"
"1","(-6600,3325)","0","standard","I8";
;
CDS_LIB"standard"
BODY_TYPE"PLUMBING"
HDL_TAP"TRUE";
"B \NAC \NWC"1;
"S \NAC"
BN"10"28;
%"TAP"
"1","(-6800,3775)","0","standard","I9";
;
CDS_LIB"standard"
BODY_TYPE"PLUMBING"
HDL_TAP"TRUE";
"B \NAC \NWC"4;
"S \NAC"
BN"11"31;
END.
